(kicad_pcb
	(version 20260206)
	(generator "pcbnew")
	(generator_version "10.0")
	(general
		(thickness 1.6)
		(legacy_teardrops no)
	)
	(paper "A4")
	(title_block
		(title "baseboard — 13948-1b.1110WZS1818.brd")
		(comment 1 "Honey Badger (Wiwynn) / footprints 234-240 of 2523")
	)
	(layers
		(0 "F.Cu" signal "TOP")
		(4 "In1.Cu" signal "L2GND")
		(6 "In2.Cu" signal "L3")
		(8 "In3.Cu" signal "L4VCC")
		(10 "In4.Cu" signal "L5VCC")
		(12 "In5.Cu" signal "L6")
		(14 "In6.Cu" signal "L7GND")
		(2 "B.Cu" signal "BOTTOM")
		(9 "F.Adhes" user "F.Adhesive")
		(11 "B.Adhes" user "B.Adhesive")
		(13 "F.Paste" user "Package Geometry/Pastemask Top")
		(15 "B.Paste" user "Package Geometry/Pastemask Bottom")
		(5 "F.SilkS" user "Ref Des/Silkscreen Top")
		(7 "B.SilkS" user "Ref Des/Silkscreen Bottom")
		(1 "F.Mask" user "Board Geometry/Soldermask Top")
		(3 "B.Mask" user "Board Geometry/Soldermask Bottom")
		(17 "Dwgs.User" user "User.Drawings")
		(19 "Cmts.User" user "User.Comments")
		(21 "Eco1.User" user "User.Eco1")
		(23 "Eco2.User" user "User.Eco2")
		(25 "Edge.Cuts" user "Board Geometry/Outline")
		(27 "Margin" user)
		(31 "F.CrtYd" user "Package Geometry/Place Bound Top")
		(29 "B.CrtYd" user "Package Geometry/Place Bound Bottom")
		(35 "F.Fab" user "Ref Des/Assembly Top")
		(33 "B.Fab" user "Ref Des/Assembly Bottom")
	)
	(footprint ""
		(layer "F.Cu")
		(at 78.8924 -11.3792 90)
		(property "Reference" "PC206"
			(at 0 0 90)
			(layer "F.SilkS")
			(hide yes)
			(effects
				(font
					(size 1.27 1.27)
				)
			)
		)
		(property "Value" "SC10U25V6KX-1GP"
			(at -0.0762 -5.1308 90)
			(unlocked yes)
			(layer "F.Fab")
			(hide yes)
			(effects
				(font
					(size 1.016 1.016)
					(thickness 0.1524)
				)
			)
		)
		(property "Device Type" "C1206H71"
			(at -0.127 -6.6548 90)
			(unlocked yes)
			(layer "F.Fab")
			(hide yes)
			(effects
				(font
					(size 1.016 1.016)
					(thickness 0.1524)
				)
			)
		)
		(duplicate_pad_numbers_are_jumpers no)
		(fp_line
			(start 1.016 -2.2352)
			(end 1.016 -0.8382)
			(stroke
				(width 0.1524)
				(type default)
			)
			(layer "F.SilkS")
		)
		(fp_line
			(start -1.016 -2.2352)
			(end 1.016 -2.2352)
			(stroke
				(width 0.1524)
				(type default)
			)
			(layer "F.SilkS")
		)
		(fp_line
			(start -1.016 -0.8382)
			(end -1.016 -2.2352)
			(stroke
				(width 0.1524)
				(type default)
			)
			(layer "F.SilkS")
		)
		(fp_line
			(start 1.016 0.8382)
			(end 1.016 2.2352)
			(stroke
				(width 0.1524)
				(type default)
			)
			(layer "F.SilkS")
		)
		(fp_line
			(start 1.016 2.2352)
			(end -1.016 2.2352)
			(stroke
				(width 0.1524)
				(type default)
			)
			(layer "F.SilkS")
		)
		(fp_line
			(start -1.016 2.2352)
			(end -1.016 0.8382)
			(stroke
				(width 0.1524)
				(type default)
			)
			(layer "F.SilkS")
		)
		(fp_rect
			(start -1.0922 2.3114)
			(end 1.0922 -2.3114)
			(stroke
				(width 0)
				(type default)
			)
			(fill no)
			(layer "F.CrtYd")
		)
		(fp_poly
			(pts
				(xy 1.0922 -2.3114) (xy 1.0922 2.3114) (xy -1.0922 2.3114) (xy -1.0922 -2.3114)
			)
			(stroke
				(width 0)
				(type default)
			)
			(fill no)
			(layer "F.Fab")
		)
		(pad "1" smd rect
			(at 0 -1.397 90)
			(size 1.651 1.27)
			(layers "F.Cu" "F.Mask" "F.Paste")
			(net "VT235_VDDH")
		)
		(pad "2" smd rect
			(at 0 1.397 90)
			(size 1.651 1.27)
			(layers "F.Cu" "F.Mask" "F.Paste")
			(net "GND")
		)
	)
	(footprint ""
		(layer "F.Cu")
		(at 179.569872 -195.194936 -90)
		(property "Reference" "U24"
			(at 0 0 270)
			(layer "F.SilkS")
			(hide yes)
			(effects
				(font
					(size 1.27 1.27)
				)
			)
		)
		(property "Value" "PCA9511ADP-T-GP"
			(at 0 -13.1572 270)
			(unlocked yes)
			(layer "F.Fab")
			(hide yes)
			(effects
				(font
					(size 1.016 1.016)
					(thickness 0.1524)
				)
			)
		)
		(property "Device Type" "SSOIC8-2H44"
			(at 0 -15.1892 270)
			(unlocked yes)
			(layer "F.Fab")
			(hide yes)
			(effects
				(font
					(size 1.016 1.016)
					(thickness 0.1524)
				)
			)
		)
		(duplicate_pad_numbers_are_jumpers no)
		(fp_line
			(start -1.7018 1.0414)
			(end -1.7018 2.9718)
			(stroke
				(width 0.635)
				(type default)
			)
			(layer "F.SilkS")
		)
		(fp_line
			(start -1.9304 1.016)
			(end -1.9304 -1.016)
			(stroke
				(width 0.1524)
				(type default)
			)
			(layer "F.SilkS")
		)
		(fp_line
			(start 1.0922 1.016)
			(end -1.9304 1.016)
			(stroke
				(width 0.1524)
				(type default)
			)
			(layer "F.SilkS")
		)
		(fp_line
			(start -1.524 0)
			(end -1.9304 0.4064)
			(stroke
				(width 0.1524)
				(type default)
			)
			(layer "F.SilkS")
		)
		(fp_line
			(start -1.524 0)
			(end -1.9304 -0.4064)
			(stroke
				(width 0.1524)
				(type default)
			)
			(layer "F.SilkS")
		)
		(fp_line
			(start -1.9304 -1.016)
			(end 1.0922 -1.016)
			(stroke
				(width 0.1524)
				(type default)
			)
			(layer "F.SilkS")
		)
		(fp_line
			(start 1.0922 -1.016)
			(end 1.0922 1.016)
			(stroke
				(width 0.1524)
				(type default)
			)
			(layer "F.SilkS")
		)
		(fp_poly
			(pts
				(xy -1.1938 -1.016) (xy 1.0922 -1.016) (xy 1.0922 1.016) (xy -1.1938 1.016)
			)
			(stroke
				(width 0)
				(type default)
			)
			(fill yes)
			(layer "F.SilkS")
		)
		(fp_rect
			(start -2.0066 3.3401)
			(end 2.0066 -3.3401)
			(stroke
				(width 0)
				(type default)
			)
			(fill no)
			(layer "F.CrtYd")
		)
		(fp_poly
			(pts
				(xy -2.0066 -3.3401) (xy 2.0066 -3.3401) (xy 2.0066 3.3401) (xy -2.0066 3.3401)
			)
			(stroke
				(width 0)
				(type default)
			)
			(fill no)
			(layer "F.Fab")
		)
		(pad "1" smd rect
			(at -0.97536 2.0701 270)
			(size 0.4064 1.524)
			(layers "F.Cu" "F.Mask" "F.Paste")
			(net "I2C_C_BUFF_EN")
		)
		(pad "2" smd rect
			(at -0.32512 2.0701 270)
			(size 0.4064 1.524)
			(layers "F.Cu" "F.Mask" "F.Paste")
			(net "BMC_I2C_C_SCL")
		)
		(pad "3" smd rect
			(at 0.32512 2.0701 270)
			(size 0.4064 1.524)
			(layers "F.Cu" "F.Mask" "F.Paste")
			(net "SAS_I2C_C_BUF_SCL")
		)
		(pad "4" smd rect
			(at 0.97536 2.0701 270)
			(size 0.4064 1.524)
			(layers "F.Cu" "F.Mask" "F.Paste")
			(net "GND")
		)
		(pad "5" smd rect
			(at 0.97536 -2.0701 270)
			(size 0.4064 1.524)
			(layers "F.Cu" "F.Mask" "F.Paste")
			(net "I2C_C_BUF_READY")
		)
		(pad "6" smd rect
			(at 0.32512 -2.0701 270)
			(size 0.4064 1.524)
			(layers "F.Cu" "F.Mask" "F.Paste")
			(net "SAS_I2C_C_BUF_SDA")
		)
		(pad "7" smd rect
			(at -0.32512 -2.0701 270)
			(size 0.4064 1.524)
			(layers "F.Cu" "F.Mask" "F.Paste")
			(net "BMC_I2C_C_SDA")
		)
		(pad "8" smd rect
			(at -0.97536 -2.0701 270)
			(size 0.4064 1.524)
			(layers "F.Cu" "F.Mask" "F.Paste")
			(net "P3V3_STBY")
		)
	)
	(footprint ""
		(layer "F.Cu")
		(at 173.630844 -27.366976 90)
		(property "Reference" "R405"
			(at 0 0 90)
			(layer "F.SilkS")
			(hide yes)
			(effects
				(font
					(size 1.27 1.27)
				)
			)
		)
		(property "Value" "49D9R2F-GP"
			(at 0.064008 -3.993896 90)
			(unlocked yes)
			(layer "F.Fab")
			(hide yes)
			(effects
				(font
					(size 1.016 1.016)
					(thickness 0.1524)
				)
			)
		)
		(property "Device Type" "R402H16"
			(at 0.064008 -5.517896 90)
			(unlocked yes)
			(layer "F.Fab")
			(hide yes)
			(effects
				(font
					(size 1.016 1.016)
					(thickness 0.1524)
				)
			)
		)
		(duplicate_pad_numbers_are_jumpers no)
		(fp_line
			(start 0.508 -0.9398)
			(end -0.508 -0.9398)
			(stroke
				(width 0.1524)
				(type default)
			)
			(layer "F.SilkS")
		)
		(fp_line
			(start -0.508 -0.9398)
			(end -0.508 0.9398)
			(stroke
				(width 0.1524)
				(type default)
			)
			(layer "F.SilkS")
		)
		(fp_rect
			(start -0.508 0.9398)
			(end 0.508 -0.9398)
			(stroke
				(width 0)
				(type default)
			)
			(fill no)
			(layer "F.CrtYd")
		)
		(fp_rect
			(start -0.508 0.9398)
			(end 0.508 -0.9398)
			(stroke
				(width 0)
				(type default)
			)
			(fill no)
			(layer "F.Fab")
		)
		(pad "1" smd custom
			(at 0 -0.4445 90)
			(size 0.1397 0.1397)
			(layers "F.Cu" "F.Mask" "F.Paste")
			(net "MOD_IMC_FAB_D_COP")
			(options
				(clearance outline)
				(anchor circle)
			)
			(primitives
				(gr_poly
					(pts
						(arc
							(start -0.1778 -0.2794)
							(mid -0.249642 -0.249642)
							(end -0.2794 -0.1778)
						)
						(arc
							(start -0.2794 0.1778)
							(mid -0.249642 0.249642)
							(end -0.1778 0.2794)
						)
						(arc
							(start 0.1778 0.2794)
							(mid 0.249642 0.249642)
							(end 0.2794 0.1778)
						)
						(arc
							(start 0.2794 -0.1778)
							(mid 0.249642 -0.249642)
							(end 0.1778 -0.2794)
						)
					)
					(width 0)
					(fill yes)
				)
			)
		)
		(pad "2" smd custom
			(at 0 0.4445 90)
			(size 0.1397 0.1397)
			(layers "F.Cu" "F.Mask" "F.Paste")
			(net "BCM5221_TX_C_DN")
			(options
				(clearance outline)
				(anchor circle)
			)
			(primitives
				(gr_poly
					(pts
						(arc
							(start -0.1778 -0.2794)
							(mid -0.249642 -0.249642)
							(end -0.2794 -0.1778)
						)
						(arc
							(start -0.2794 0.1778)
							(mid -0.249642 0.249642)
							(end -0.1778 0.2794)
						)
						(arc
							(start 0.1778 0.2794)
							(mid 0.249642 0.249642)
							(end 0.2794 0.1778)
						)
						(arc
							(start 0.2794 -0.1778)
							(mid 0.249642 -0.249642)
							(end 0.1778 -0.2794)
						)
					)
					(width 0)
					(fill yes)
				)
			)
		)
	)
	(footprint ""
		(layer "F.Cu")
		(at 92.27947 -102.93858 90)
		(property "Reference" "SR816"
			(at 0 0 90)
			(layer "F.SilkS")
			(hide yes)
			(effects
				(font
					(size 1.27 1.27)
				)
			)
		)
		(property "Value" "4K75R2F-1-GP"
			(at 0.064008 -3.993896 90)
			(unlocked yes)
			(layer "F.Fab")
			(hide yes)
			(effects
				(font
					(size 1.016 1.016)
					(thickness 0.1524)
				)
			)
		)
		(property "Device Type" "R402H16"
			(at 0.064008 -5.517896 90)
			(unlocked yes)
			(layer "F.Fab")
			(hide yes)
			(effects
				(font
					(size 1.016 1.016)
					(thickness 0.1524)
				)
			)
		)
		(duplicate_pad_numbers_are_jumpers no)
		(fp_line
			(start 0.508 -0.9398)
			(end -0.508 -0.9398)
			(stroke
				(width 0.1524)
				(type default)
			)
			(layer "F.SilkS")
		)
		(fp_line
			(start -0.508 -0.9398)
			(end -0.508 0.9398)
			(stroke
				(width 0.1524)
				(type default)
			)
			(layer "F.SilkS")
		)
		(fp_rect
			(start -0.508 0.9398)
			(end 0.508 -0.9398)
			(stroke
				(width 0)
				(type default)
			)
			(fill no)
			(layer "F.CrtYd")
		)
		(fp_rect
			(start -0.508 0.9398)
			(end 0.508 -0.9398)
			(stroke
				(width 0)
				(type default)
			)
			(fill no)
			(layer "F.Fab")
		)
		(pad "1" smd custom
			(at 0 -0.4445 90)
			(size 0.1397 0.1397)
			(layers "F.Cu" "F.Mask" "F.Paste")
			(net "P1V8_E")
			(options
				(clearance outline)
				(anchor circle)
			)
			(primitives
				(gr_poly
					(pts
						(arc
							(start -0.1778 -0.2794)
							(mid -0.249642 -0.249642)
							(end -0.2794 -0.1778)
						)
						(arc
							(start -0.2794 0.1778)
							(mid -0.249642 0.249642)
							(end -0.1778 0.2794)
						)
						(arc
							(start 0.1778 0.2794)
							(mid 0.249642 0.249642)
							(end 0.2794 0.1778)
						)
						(arc
							(start 0.2794 -0.1778)
							(mid 0.249642 -0.249642)
							(end 0.1778 -0.2794)
						)
					)
					(width 0)
					(fill yes)
				)
			)
		)
		(pad "2" smd custom
			(at 0 0.4445 90)
			(size 0.1397 0.1397)
			(layers "F.Cu" "F.Mask" "F.Paste")
			(net "SDB_RX")
			(options
				(clearance outline)
				(anchor circle)
			)
			(primitives
				(gr_poly
					(pts
						(arc
							(start -0.1778 -0.2794)
							(mid -0.249642 -0.249642)
							(end -0.2794 -0.1778)
						)
						(arc
							(start -0.2794 0.1778)
							(mid -0.249642 0.249642)
							(end -0.1778 0.2794)
						)
						(arc
							(start 0.1778 0.2794)
							(mid 0.249642 0.249642)
							(end 0.2794 0.1778)
						)
						(arc
							(start 0.2794 -0.1778)
							(mid 0.249642 -0.249642)
							(end 0.1778 -0.2794)
						)
					)
					(width 0)
					(fill yes)
				)
			)
		)
	)
	(footprint ""
		(layer "F.Cu")
		(at 53.594 -209.042 -90)
		(property "Reference" "C339"
			(at 0 0 270)
			(layer "F.SilkS")
			(hide yes)
			(effects
				(font
					(size 1.27 1.27)
				)
			)
		)
		(property "Value" "SC22U6D3V5MX-2GP"
			(at -0.0762 -6.1214 270)
			(unlocked yes)
			(layer "F.Fab")
			(hide yes)
			(effects
				(font
					(size 1.016 1.016)
					(thickness 0.1524)
				)
			)
		)
		(property "Device Type" "C805H58"
			(at -0.0762 -8.1534 270)
			(unlocked yes)
			(layer "F.Fab")
			(hide yes)
			(effects
				(font
					(size 1.016 1.016)
					(thickness 0.1524)
				)
			)
		)
		(duplicate_pad_numbers_are_jumpers no)
		(fp_line
			(start 0.635 0)
			(end -0.635 0)
			(stroke
				(width 0.508)
				(type default)
			)
			(layer "F.SilkS")
		)
		(fp_rect
			(start -0.9652 1.778)
			(end 0.9652 -1.778)
			(stroke
				(width 0)
				(type default)
			)
			(fill no)
			(layer "F.CrtYd")
		)
		(fp_poly
			(pts
				(xy -0.9652 -1.778) (xy 0.9652 -1.778) (xy 0.9652 1.778) (xy -0.9652 1.778)
			)
			(stroke
				(width 0)
				(type default)
			)
			(fill no)
			(layer "F.Fab")
		)
		(pad "1" smd rect
			(at 0 -0.9652 270)
			(size 1.397 1.143)
			(layers "F.Cu" "F.Mask" "F.Paste")
			(net "MB0_HS_ENABLE")
		)
		(pad "2" smd rect
			(at 0 0.9652 270)
			(size 1.397 1.143)
			(layers "F.Cu" "F.Mask" "F.Paste")
			(net "GND")
		)
	)
	(footprint ""
		(layer "F.Cu")
		(at 273.177 -225.552)
		(property "Reference" "PR77"
			(at 0 0 0)
			(layer "F.SilkS")
			(hide yes)
			(effects
				(font
					(size 1.27 1.27)
				)
			)
		)
		(property "Value" "0R6J-3-GP"
			(at -0.0508 -4.8514 0)
			(unlocked yes)
			(layer "F.Fab")
			(hide yes)
			(effects
				(font
					(size 1.016 1.016)
					(thickness 0.1524)
				)
			)
		)
		(property "Device Type" "R1206H28"
			(at 0 -6.3754 0)
			(unlocked yes)
			(layer "F.Fab")
			(hide yes)
			(effects
				(font
					(size 1.016 1.016)
					(thickness 0.1524)
				)
			)
		)
		(duplicate_pad_numbers_are_jumpers no)
		(fp_line
			(start -1.016 -2.2352)
			(end 1.016 -2.2352)
			(stroke
				(width 0.1524)
				(type default)
			)
			(layer "F.SilkS")
		)
		(fp_line
			(start -1.016 2.2352)
			(end -1.016 -2.2352)
			(stroke
				(width 0.1524)
				(type default)
			)
			(layer "F.SilkS")
		)
		(fp_line
			(start 1.016 -2.2352)
			(end 1.016 2.2352)
			(stroke
				(width 0.1524)
				(type default)
			)
			(layer "F.SilkS")
		)
		(fp_line
			(start 1.016 2.2352)
			(end -1.016 2.2352)
			(stroke
				(width 0.1524)
				(type default)
			)
			(layer "F.SilkS")
		)
		(fp_rect
			(start -1.0922 2.3114)
			(end 1.0922 -2.3114)
			(stroke
				(width 0)
				(type default)
			)
			(fill no)
			(layer "F.CrtYd")
		)
		(fp_poly
			(pts
				(xy -1.0922 -2.3114) (xy 1.0922 -2.3114) (xy 1.0922 2.3114) (xy -1.0922 2.3114)
			)
			(stroke
				(width 0)
				(type default)
			)
			(fill no)
			(layer "F.Fab")
		)
		(pad "1" smd rect
			(at 0 -1.397)
			(size 1.651 1.27)
			(layers "F.Cu" "F.Mask" "F.Paste")
			(net "P1V8_STBY")
		)
		(pad "2" smd rect
			(at 0 1.397)
			(size 1.651 1.27)
			(layers "F.Cu" "F.Mask" "F.Paste")
			(net "TPS74801_P1V53_STBY_IN")
		)
	)
	(footprint ""
		(layer "F.Cu")
		(at 299.637958 -58.293 180)
		(property "Reference" "C285"
			(at 0 0 180)
			(layer "F.SilkS")
			(hide yes)
			(effects
				(font
					(size 1.27 1.27)
				)
			)
		)
		(property "Value" "SCD1U25V2KX-2-GP"
			(at 1.1811 -2.7051 180)
			(unlocked yes)
			(layer "F.Fab")
			(hide yes)
			(effects
				(font
					(size 1.016 1.016)
					(thickness 0.1524)
				)
			)
		)
		(property "Device Type" "C402H22"
			(at 1.1811 -4.2291 180)
			(unlocked yes)
			(layer "F.Fab")
			(hide yes)
			(effects
				(font
					(size 1.016 1.016)
					(thickness 0.1524)
				)
			)
		)
		(duplicate_pad_numbers_are_jumpers no)
		(fp_rect
			(start -0.4318 0.9525)
			(end 0.4318 -0.9525)
			(stroke
				(width 0)
				(type default)
			)
			(fill no)
			(layer "F.CrtYd")
		)
		(fp_rect
			(start -0.4318 0.9525)
			(end 0.4318 -0.9525)
			(stroke
				(width 0)
				(type default)
			)
			(fill no)
			(layer "F.Fab")
		)
		(pad "1" smd custom
			(at 0 -0.4445 180)
			(size 0.1524 0.1524)
			(layers "F.Cu" "F.Mask" "F.Paste")
			(net "P3V3_STBY")
			(options
				(clearance outline)
				(anchor circle)
			)
			(primitives
				(gr_poly
					(pts
						(arc
							(start 0.3048 -0.2032)
							(mid 0.275042 -0.275042)
							(end 0.2032 -0.3048)
						)
						(arc
							(start -0.2032 -0.3048)
							(mid -0.275042 -0.275042)
							(end -0.3048 -0.2032)
						)
						(arc
							(start -0.3048 0.2032)
							(mid -0.275042 0.275042)
							(end -0.2032 0.3048)
						)
						(arc
							(start 0.2032 0.3048)
							(mid 0.275042 0.275042)
							(end 0.3048 0.2032)
						)
					)
					(width 0)
					(fill yes)
				)
			)
		)
		(pad "2" smd custom
			(at 0 0.4445 180)
			(size 0.1524 0.1524)
			(layers "F.Cu" "F.Mask" "F.Paste")
			(net "GND")
			(options
				(clearance outline)
				(anchor circle)
			)
			(primitives
				(gr_poly
					(pts
						(arc
							(start 0.3048 -0.2032)
							(mid 0.275042 -0.275042)
							(end 0.2032 -0.3048)
						)
						(arc
							(start -0.2032 -0.3048)
							(mid -0.275042 -0.275042)
							(end -0.3048 -0.2032)
						)
						(arc
							(start -0.3048 0.2032)
							(mid -0.275042 0.275042)
							(end -0.2032 0.3048)
						)
						(arc
							(start 0.2032 0.3048)
							(mid 0.275042 0.275042)
							(end 0.3048 0.2032)
						)
					)
					(width 0)
					(fill yes)
				)
			)
		)
	)
)
